(kicad_pcb
	(version 20260206)
	(generator "pcbnew")
	(generator_version "10.0")
	(general
		(thickness 1.6)
		(legacy_teardrops no)
	)
	(paper "A4")
	(title_block
		(title "03242023_DA0F0TMBIJ0_F0T_Motherboard_J_brd_V01_OCP.brd")
		(comment 1 "Grand Teton / footprints 133-139 of 6105")
	)
	(layers
		(0 "F.Cu" signal "TOP")
		(4 "In1.Cu" signal "GND")
		(6 "In2.Cu" signal "IN1")
		(8 "In3.Cu" signal "GND1")
		(10 "In4.Cu" signal "IN2")
		(12 "In5.Cu" signal "GND2")
		(14 "In6.Cu" signal "IN3")
		(16 "In7.Cu" signal "GND3")
		(18 "In8.Cu" signal "VCC")
		(20 "In9.Cu" signal "VCC1")
		(22 "In10.Cu" signal "GND4")
		(24 "In11.Cu" signal "IN4")
		(26 "In12.Cu" signal "GND5")
		(28 "In13.Cu" signal "IN5")
		(30 "In14.Cu" signal "GND6")
		(32 "In15.Cu" signal "IN6")
		(34 "In16.Cu" signal "GND7")
		(2 "B.Cu" signal "BOTTOM")
		(9 "F.Adhes" user "F.Adhesive")
		(11 "B.Adhes" user "B.Adhesive")
		(13 "F.Paste" user "Package Geometry/Pastemask Top")
		(15 "B.Paste" user "Package Geometry/Pastemask Bottom")
		(5 "F.SilkS" user "Ref Des/Silkscreen Top")
		(7 "B.SilkS" user "Ref Des/Silkscreen Bottom")
		(1 "F.Mask" user "Board Geometry/Soldermask Top")
		(3 "B.Mask" user "Board Geometry/Soldermask Bottom")
		(17 "Dwgs.User" user "User.Drawings")
		(19 "Cmts.User" user "User.Comments")
		(21 "Eco1.User" user "User.Eco1")
		(23 "Eco2.User" user "User.Eco2")
		(25 "Edge.Cuts" user "Board Geometry/Outline")
		(27 "Margin" user)
		(31 "F.CrtYd" user "Package Geometry/Place Bound Top")
		(29 "B.CrtYd" user "Package Geometry/Place Bound Bottom")
		(35 "F.Fab" user "Ref Des/Assembly Top")
		(33 "B.Fab" user "Ref Des/Assembly Bottom")
	)
	(footprint ""
		(layer "F.Cu")
		(at 461.459834 -160.50006)
		(property "Reference" "H104"
			(at -6.563614 -4.53263 0)
			(unlocked yes)
			(layer "F.SilkS")
			(effects
				(font
					(size 0.7874 0.5842)
					(thickness 0.1524)
				)
				(justify left)
			)
		)
		(property "Value" ""
			(at 0 0 0)
			(layer "F.Fab")
			(effects
				(font
					(size 1.27 1.27)
				)
			)
		)
		(duplicate_pad_numbers_are_jumpers no)
		(pad "1" thru_hole circle
			(at 0 0)
			(size 10.0076 10.0076)
			(drill 5.6134)
			(layers "*.Cu" "*.Mask")
			(remove_unused_layers no)
			(net "GND")
			(clearance -1.9431)
		)
	)
	(footprint ""
		(layer "F.Cu")
		(at 144.320006 -77.532738)
		(property "Reference" "C1619"
			(at 0 0 0)
			(layer "F.SilkS")
			(hide yes)
			(effects
				(font
					(size 1.27 1.27)
				)
			)
		)
		(property "Value" ""
			(at 0 0 0)
			(layer "F.Fab")
			(effects
				(font
					(size 1.27 1.27)
				)
			)
		)
		(duplicate_pad_numbers_are_jumpers no)
		(fp_line
			(start -0.7874 -0.4064)
			(end 0.7874 -0.4064)
			(stroke
				(width 0.1524)
				(type default)
			)
			(layer "F.SilkS")
		)
		(fp_line
			(start -0.7874 0.4064)
			(end -0.7874 -0.4064)
			(stroke
				(width 0.1524)
				(type default)
			)
			(layer "F.SilkS")
		)
		(fp_line
			(start 0.7874 -0.4064)
			(end 0.7874 0.4064)
			(stroke
				(width 0.1524)
				(type default)
			)
			(layer "F.SilkS")
		)
		(fp_line
			(start 0.7874 0.4064)
			(end -0.7874 0.4064)
			(stroke
				(width 0.1524)
				(type default)
			)
			(layer "F.SilkS")
		)
		(fp_line
			(start -0.67945 -0.305054)
			(end -0.12065 -0.305054)
			(stroke
				(width 0.1)
				(type default)
			)
			(layer "F.Fab")
		)
		(fp_line
			(start -0.67945 0.3048)
			(end -0.67945 -0.305054)
			(stroke
				(width 0.1)
				(type default)
			)
			(layer "F.Fab")
		)
		(fp_line
			(start -0.12065 -0.305054)
			(end -0.12065 -0.2794)
			(stroke
				(width 0.1)
				(type default)
			)
			(layer "F.Fab")
		)
		(fp_line
			(start -0.12065 -0.2794)
			(end 0.12065 -0.2794)
			(stroke
				(width 0.1)
				(type default)
			)
			(layer "F.Fab")
		)
		(fp_line
			(start -0.12065 0.2794)
			(end -0.12065 0.3048)
			(stroke
				(width 0.1)
				(type default)
			)
			(layer "F.Fab")
		)
		(fp_line
			(start -0.12065 0.3048)
			(end -0.67945 0.3048)
			(stroke
				(width 0.1)
				(type default)
			)
			(layer "F.Fab")
		)
		(fp_line
			(start 0.120396 0.2794)
			(end -0.12065 0.2794)
			(stroke
				(width 0.1)
				(type default)
			)
			(layer "F.Fab")
		)
		(fp_line
			(start 0.120396 0.3048)
			(end 0.120396 0.2794)
			(stroke
				(width 0.1)
				(type default)
			)
			(layer "F.Fab")
		)
		(fp_line
			(start 0.12065 -0.3048)
			(end 0.67945 -0.3048)
			(stroke
				(width 0.1)
				(type default)
			)
			(layer "F.Fab")
		)
		(fp_line
			(start 0.12065 -0.2794)
			(end 0.12065 -0.3048)
			(stroke
				(width 0.1)
				(type default)
			)
			(layer "F.Fab")
		)
		(fp_line
			(start 0.67945 -0.3048)
			(end 0.67945 0.3048)
			(stroke
				(width 0.1)
				(type default)
			)
			(layer "F.Fab")
		)
		(fp_line
			(start 0.67945 0.3048)
			(end 0.120396 0.3048)
			(stroke
				(width 0.1)
				(type default)
			)
			(layer "F.Fab")
		)
		(pad "1" smd circle
			(at -0.40005 0)
			(size 0 0)
			(layers "F.Cu" "F.Mask" "F.Paste")
			(net "P3V3_AUX")
		)
		(pad "2" smd circle
			(at 0.40005 0)
			(size 0 0)
			(layers "F.Cu" "F.Mask" "F.Paste")
			(net "GND")
		)
	)
	(footprint ""
		(layer "F.Cu")
		(at 209.959956 -37.769292 90)
		(property "Reference" "C2014"
			(at 0 0 90)
			(layer "F.SilkS")
			(hide yes)
			(effects
				(font
					(size 1.27 1.27)
				)
			)
		)
		(property "Value" ""
			(at 0 0 90)
			(layer "F.Fab")
			(effects
				(font
					(size 1.27 1.27)
				)
			)
		)
		(duplicate_pad_numbers_are_jumpers no)
		(fp_line
			(start 0.7874 -0.4064)
			(end 0.7874 0.4064)
			(stroke
				(width 0.1524)
				(type default)
			)
			(layer "F.SilkS")
		)
		(fp_line
			(start -0.7874 -0.4064)
			(end 0.7874 -0.4064)
			(stroke
				(width 0.1524)
				(type default)
			)
			(layer "F.SilkS")
		)
		(fp_line
			(start 0.7874 0.4064)
			(end -0.7874 0.4064)
			(stroke
				(width 0.1524)
				(type default)
			)
			(layer "F.SilkS")
		)
		(fp_line
			(start -0.7874 0.4064)
			(end -0.7874 -0.4064)
			(stroke
				(width 0.1524)
				(type default)
			)
			(layer "F.SilkS")
		)
		(fp_line
			(start -0.12065 -0.305054)
			(end -0.12065 -0.2794)
			(stroke
				(width 0.1)
				(type default)
			)
			(layer "F.Fab")
		)
		(fp_line
			(start -0.67945 -0.305054)
			(end -0.12065 -0.305054)
			(stroke
				(width 0.1)
				(type default)
			)
			(layer "F.Fab")
		)
		(fp_line
			(start 0.67945 -0.3048)
			(end 0.67945 0.3048)
			(stroke
				(width 0.1)
				(type default)
			)
			(layer "F.Fab")
		)
		(fp_line
			(start 0.12065 -0.3048)
			(end 0.67945 -0.3048)
			(stroke
				(width 0.1)
				(type default)
			)
			(layer "F.Fab")
		)
		(fp_line
			(start 0.12065 -0.2794)
			(end 0.12065 -0.3048)
			(stroke
				(width 0.1)
				(type default)
			)
			(layer "F.Fab")
		)
		(fp_line
			(start -0.12065 -0.2794)
			(end 0.12065 -0.2794)
			(stroke
				(width 0.1)
				(type default)
			)
			(layer "F.Fab")
		)
		(fp_line
			(start 0.120396 0.2794)
			(end -0.12065 0.2794)
			(stroke
				(width 0.1)
				(type default)
			)
			(layer "F.Fab")
		)
		(fp_line
			(start -0.12065 0.2794)
			(end -0.12065 0.3048)
			(stroke
				(width 0.1)
				(type default)
			)
			(layer "F.Fab")
		)
		(fp_line
			(start 0.67945 0.3048)
			(end 0.120396 0.3048)
			(stroke
				(width 0.1)
				(type default)
			)
			(layer "F.Fab")
		)
		(fp_line
			(start 0.120396 0.3048)
			(end 0.120396 0.2794)
			(stroke
				(width 0.1)
				(type default)
			)
			(layer "F.Fab")
		)
		(fp_line
			(start -0.12065 0.3048)
			(end -0.67945 0.3048)
			(stroke
				(width 0.1)
				(type default)
			)
			(layer "F.Fab")
		)
		(fp_line
			(start -0.67945 0.3048)
			(end -0.67945 -0.305054)
			(stroke
				(width 0.1)
				(type default)
			)
			(layer "F.Fab")
		)
		(pad "1" smd circle
			(at -0.40005 0 90)
			(size 0 0)
			(layers "F.Cu" "F.Mask" "F.Paste")
			(net "P3V3_AUX")
		)
		(pad "2" smd circle
			(at 0.40005 0 90)
			(size 0 0)
			(layers "F.Cu" "F.Mask" "F.Paste")
			(net "GND")
		)
	)
	(footprint ""
		(layer "F.Cu")
		(at 131.6736 -124.234448 180)
		(property "Reference" "R3150"
			(at 0 0 180)
			(layer "F.SilkS")
			(hide yes)
			(effects
				(font
					(size 1.27 1.27)
				)
			)
		)
		(property "Value" ""
			(at 0 0 180)
			(layer "F.Fab")
			(effects
				(font
					(size 1.27 1.27)
				)
			)
		)
		(duplicate_pad_numbers_are_jumpers no)
		(fp_line
			(start 0.7874 0.4064)
			(end -0.7874 0.4064)
			(stroke
				(width 0.1524)
				(type default)
			)
			(layer "F.SilkS")
		)
		(fp_line
			(start 0.7874 -0.4064)
			(end 0.7874 0.4064)
			(stroke
				(width 0.1524)
				(type default)
			)
			(layer "F.SilkS")
		)
		(fp_line
			(start -0.7874 0.4064)
			(end -0.7874 -0.4064)
			(stroke
				(width 0.1524)
				(type default)
			)
			(layer "F.SilkS")
		)
		(fp_line
			(start -0.7874 -0.4064)
			(end 0.7874 -0.4064)
			(stroke
				(width 0.1524)
				(type default)
			)
			(layer "F.SilkS")
		)
		(fp_line
			(start 0.67945 0.3048)
			(end 0.120396 0.3048)
			(stroke
				(width 0.1)
				(type default)
			)
			(layer "F.Fab")
		)
		(fp_line
			(start 0.67945 -0.3048)
			(end 0.67945 0.3048)
			(stroke
				(width 0.1)
				(type default)
			)
			(layer "F.Fab")
		)
		(fp_line
			(start 0.12065 -0.2794)
			(end 0.12065 -0.3048)
			(stroke
				(width 0.1)
				(type default)
			)
			(layer "F.Fab")
		)
		(fp_line
			(start 0.12065 -0.3048)
			(end 0.67945 -0.3048)
			(stroke
				(width 0.1)
				(type default)
			)
			(layer "F.Fab")
		)
		(fp_line
			(start 0.120396 0.3048)
			(end 0.120396 0.2794)
			(stroke
				(width 0.1)
				(type default)
			)
			(layer "F.Fab")
		)
		(fp_line
			(start 0.120396 0.2794)
			(end -0.12065 0.2794)
			(stroke
				(width 0.1)
				(type default)
			)
			(layer "F.Fab")
		)
		(fp_line
			(start -0.12065 0.3048)
			(end -0.67945 0.3048)
			(stroke
				(width 0.1)
				(type default)
			)
			(layer "F.Fab")
		)
		(fp_line
			(start -0.12065 0.2794)
			(end -0.12065 0.3048)
			(stroke
				(width 0.1)
				(type default)
			)
			(layer "F.Fab")
		)
		(fp_line
			(start -0.12065 -0.2794)
			(end 0.12065 -0.2794)
			(stroke
				(width 0.1)
				(type default)
			)
			(layer "F.Fab")
		)
		(fp_line
			(start -0.12065 -0.305054)
			(end -0.12065 -0.2794)
			(stroke
				(width 0.1)
				(type default)
			)
			(layer "F.Fab")
		)
		(fp_line
			(start -0.67945 0.3048)
			(end -0.67945 -0.305054)
			(stroke
				(width 0.1)
				(type default)
			)
			(layer "F.Fab")
		)
		(fp_line
			(start -0.67945 -0.305054)
			(end -0.12065 -0.305054)
			(stroke
				(width 0.1)
				(type default)
			)
			(layer "F.Fab")
		)
		(pad "1" smd circle
			(at -0.40005 0 180)
			(size 0 0)
			(layers "F.Cu" "F.Mask" "F.Paste")
			(net "PD_SMB_OCP2_HP_ADD2")
		)
		(pad "2" smd circle
			(at 0.40005 0 180)
			(size 0 0)
			(layers "F.Cu" "F.Mask" "F.Paste")
			(net "GND")
		)
	)
	(footprint ""
		(layer "F.Cu")
		(at 285.211266 -362.584746 -90)
		(property "Reference" "PC1214_P0_4"
			(at 0 0 270)
			(layer "F.SilkS")
			(hide yes)
			(effects
				(font
					(size 1.27 1.27)
				)
			)
		)
		(property "Value" ""
			(at 0 0 270)
			(layer "F.Fab")
			(effects
				(font
					(size 1.27 1.27)
				)
			)
		)
		(duplicate_pad_numbers_are_jumpers no)
		(fp_line
			(start -0.7874 0.4064)
			(end -0.7874 -0.4064)
			(stroke
				(width 0.1524)
				(type default)
			)
			(layer "F.SilkS")
		)
		(fp_line
			(start 0.7874 0.4064)
			(end -0.7874 0.4064)
			(stroke
				(width 0.1524)
				(type default)
			)
			(layer "F.SilkS")
		)
		(fp_line
			(start -0.7874 -0.4064)
			(end 0.7874 -0.4064)
			(stroke
				(width 0.1524)
				(type default)
			)
			(layer "F.SilkS")
		)
		(fp_line
			(start 0.7874 -0.4064)
			(end 0.7874 0.4064)
			(stroke
				(width 0.1524)
				(type default)
			)
			(layer "F.SilkS")
		)
		(fp_line
			(start -0.67945 0.3048)
			(end -0.67945 -0.305054)
			(stroke
				(width 0.1)
				(type default)
			)
			(layer "F.Fab")
		)
		(fp_line
			(start -0.12065 0.3048)
			(end -0.67945 0.3048)
			(stroke
				(width 0.1)
				(type default)
			)
			(layer "F.Fab")
		)
		(fp_line
			(start 0.120396 0.3048)
			(end 0.120396 0.2794)
			(stroke
				(width 0.1)
				(type default)
			)
			(layer "F.Fab")
		)
		(fp_line
			(start 0.67945 0.3048)
			(end 0.120396 0.3048)
			(stroke
				(width 0.1)
				(type default)
			)
			(layer "F.Fab")
		)
		(fp_line
			(start -0.12065 0.2794)
			(end -0.12065 0.3048)
			(stroke
				(width 0.1)
				(type default)
			)
			(layer "F.Fab")
		)
		(fp_line
			(start 0.120396 0.2794)
			(end -0.12065 0.2794)
			(stroke
				(width 0.1)
				(type default)
			)
			(layer "F.Fab")
		)
		(fp_line
			(start -0.12065 -0.2794)
			(end 0.12065 -0.2794)
			(stroke
				(width 0.1)
				(type default)
			)
			(layer "F.Fab")
		)
		(fp_line
			(start 0.12065 -0.2794)
			(end 0.12065 -0.3048)
			(stroke
				(width 0.1)
				(type default)
			)
			(layer "F.Fab")
		)
		(fp_line
			(start 0.12065 -0.3048)
			(end 0.67945 -0.3048)
			(stroke
				(width 0.1)
				(type default)
			)
			(layer "F.Fab")
		)
		(fp_line
			(start 0.67945 -0.3048)
			(end 0.67945 0.3048)
			(stroke
				(width 0.1)
				(type default)
			)
			(layer "F.Fab")
		)
		(fp_line
			(start -0.67945 -0.305054)
			(end -0.12065 -0.305054)
			(stroke
				(width 0.1)
				(type default)
			)
			(layer "F.Fab")
		)
		(fp_line
			(start -0.12065 -0.305054)
			(end -0.12065 -0.2794)
			(stroke
				(width 0.1)
				(type default)
			)
			(layer "F.Fab")
		)
		(pad "1" smd circle
			(at -0.40005 0 270)
			(size 0 0)
			(layers "F.Cu" "F.Mask" "F.Paste")
			(net "PVCCFA_EHV_FIVRA_CPU0_PVCC2")
		)
		(pad "2" smd circle
			(at 0.40005 0 270)
			(size 0 0)
			(layers "F.Cu" "F.Mask" "F.Paste")
			(net "GND")
		)
	)
	(footprint ""
		(layer "F.Cu")
		(at 146.896074 -408.517344 -90)
		(property "Reference" "C1533"
			(at 0 0 270)
			(layer "F.SilkS")
			(hide yes)
			(effects
				(font
					(size 1.27 1.27)
				)
			)
		)
		(property "Value" ""
			(at 0 0 270)
			(layer "F.Fab")
			(effects
				(font
					(size 1.27 1.27)
				)
			)
		)
		(duplicate_pad_numbers_are_jumpers no)
		(fp_line
			(start -0.299974 0.150114)
			(end -0.299974 -0.150114)
			(stroke
				(width 0.1)
				(type default)
			)
			(layer "F.Fab")
		)
		(fp_line
			(start 0.299974 0.150114)
			(end -0.299974 0.150114)
			(stroke
				(width 0.1)
				(type default)
			)
			(layer "F.Fab")
		)
		(fp_line
			(start -0.299974 -0.150114)
			(end 0.299974 -0.150114)
			(stroke
				(width 0.1)
				(type default)
			)
			(layer "F.Fab")
		)
		(fp_line
			(start 0.299974 -0.150114)
			(end 0.299974 0.150114)
			(stroke
				(width 0.1)
				(type default)
			)
			(layer "F.Fab")
		)
		(pad "1" smd rect
			(at -0.2667 0 270)
			(size 0.3048 0.381)
			(layers "F.Cu" "F.Mask" "F.Paste")
			(net "P5E_CPU1_PE3_TX_C_DP<7>")
		)
		(pad "2" smd rect
			(at 0.2667 0 270)
			(size 0.3048 0.381)
			(layers "F.Cu" "F.Mask" "F.Paste")
			(net "P5E_CPU1_PE3_TX_DP<7>")
		)
	)
	(footprint ""
		(layer "F.Cu")
		(at 367.44783 -238.162338 90)
		(property "Reference" "C408"
			(at 0 0 90)
			(layer "F.SilkS")
			(hide yes)
			(effects
				(font
					(size 1.27 1.27)
				)
			)
		)
		(property "Value" ""
			(at 0 0 90)
			(layer "F.Fab")
			(effects
				(font
					(size 1.27 1.27)
				)
			)
		)
		(duplicate_pad_numbers_are_jumpers no)
		(fp_line
			(start 0.7874 -0.4064)
			(end 0.7874 0.4064)
			(stroke
				(width 0.1524)
				(type default)
			)
			(layer "F.SilkS")
		)
		(fp_line
			(start -0.7874 -0.4064)
			(end 0.7874 -0.4064)
			(stroke
				(width 0.1524)
				(type default)
			)
			(layer "F.SilkS")
		)
		(fp_line
			(start 0.7874 0.4064)
			(end -0.7874 0.4064)
			(stroke
				(width 0.1524)
				(type default)
			)
			(layer "F.SilkS")
		)
		(fp_line
			(start -0.7874 0.4064)
			(end -0.7874 -0.4064)
			(stroke
				(width 0.1524)
				(type default)
			)
			(layer "F.SilkS")
		)
		(fp_line
			(start -0.12065 -0.305054)
			(end -0.12065 -0.2794)
			(stroke
				(width 0.1)
				(type default)
			)
			(layer "F.Fab")
		)
		(fp_line
			(start -0.67945 -0.305054)
			(end -0.12065 -0.305054)
			(stroke
				(width 0.1)
				(type default)
			)
			(layer "F.Fab")
		)
		(fp_line
			(start 0.67945 -0.3048)
			(end 0.67945 0.3048)
			(stroke
				(width 0.1)
				(type default)
			)
			(layer "F.Fab")
		)
		(fp_line
			(start 0.12065 -0.3048)
			(end 0.67945 -0.3048)
			(stroke
				(width 0.1)
				(type default)
			)
			(layer "F.Fab")
		)
		(fp_line
			(start 0.12065 -0.2794)
			(end 0.12065 -0.3048)
			(stroke
				(width 0.1)
				(type default)
			)
			(layer "F.Fab")
		)
		(fp_line
			(start -0.12065 -0.2794)
			(end 0.12065 -0.2794)
			(stroke
				(width 0.1)
				(type default)
			)
			(layer "F.Fab")
		)
		(fp_line
			(start 0.120396 0.2794)
			(end -0.12065 0.2794)
			(stroke
				(width 0.1)
				(type default)
			)
			(layer "F.Fab")
		)
		(fp_line
			(start -0.12065 0.2794)
			(end -0.12065 0.3048)
			(stroke
				(width 0.1)
				(type default)
			)
			(layer "F.Fab")
		)
		(fp_line
			(start 0.67945 0.3048)
			(end 0.120396 0.3048)
			(stroke
				(width 0.1)
				(type default)
			)
			(layer "F.Fab")
		)
		(fp_line
			(start 0.120396 0.3048)
			(end 0.120396 0.2794)
			(stroke
				(width 0.1)
				(type default)
			)
			(layer "F.Fab")
		)
		(fp_line
			(start -0.12065 0.3048)
			(end -0.67945 0.3048)
			(stroke
				(width 0.1)
				(type default)
			)
			(layer "F.Fab")
		)
		(fp_line
			(start -0.67945 0.3048)
			(end -0.67945 -0.305054)
			(stroke
				(width 0.1)
				(type default)
			)
			(layer "F.Fab")
		)
		(pad "1" smd circle
			(at -0.40005 0 90)
			(size 0 0)
			(layers "F.Cu" "F.Mask" "F.Paste")
			(net "PVCCINFAON_CPU0")
		)
		(pad "2" smd circle
			(at 0.40005 0 90)
			(size 0 0)
			(layers "F.Cu" "F.Mask" "F.Paste")
			(net "GND")
		)
	)
)
